(kicad_pcb
	(version 20260206)
	(generator "pcbnew")
	(generator_version "10.0")
	(general
		(thickness 1.6)
		(legacy_teardrops no)
	)
	(paper "A4")
	(title_block
		(title "dpb — 14545-sa.0730WZS0815.brd")
		(comment 1 "Honey Badger (Wiwynn) / footprints 65-72 of 1066")
	)
	(layers
		(0 "F.Cu" signal "TOP")
		(4 "In1.Cu" signal "L2GND")
		(6 "In2.Cu" signal "L3")
		(8 "In3.Cu" signal "L4VCC")
		(10 "In4.Cu" signal "L5VCC")
		(12 "In5.Cu" signal "L6")
		(14 "In6.Cu" signal "L7GND")
		(2 "B.Cu" signal "BOTTOM")
		(9 "F.Adhes" user "F.Adhesive")
		(11 "B.Adhes" user "B.Adhesive")
		(13 "F.Paste" user "Package Geometry/Pastemask Top")
		(15 "B.Paste" user "Package Geometry/Pastemask Bottom")
		(5 "F.SilkS" user "Ref Des/Silkscreen Top")
		(7 "B.SilkS" user "Ref Des/Silkscreen Bottom")
		(1 "F.Mask" user "Board Geometry/Soldermask Top")
		(3 "B.Mask" user "Board Geometry/Soldermask Bottom")
		(17 "Dwgs.User" user "User.Drawings")
		(19 "Cmts.User" user "User.Comments")
		(21 "Eco1.User" user "User.Eco1")
		(23 "Eco2.User" user "User.Eco2")
		(25 "Edge.Cuts" user "Board Geometry/Outline")
		(27 "Margin" user)
		(31 "F.CrtYd" user "Package Geometry/Place Bound Top")
		(29 "B.CrtYd" user "Package Geometry/Place Bound Bottom")
		(35 "F.Fab" user "Ref Des/Assembly Top")
		(33 "B.Fab" user "Ref Des/Assembly Bottom")
	)
	(footprint ""
		(layer "F.Cu")
		(at 42.544746 -212.118702 180)
		(property "Reference" "R277"
			(at 0 0 180)
			(layer "F.SilkS")
			(hide yes)
			(effects
				(font
					(size 1.27 1.27)
				)
			)
		)
		(property "Value" "1KR2F-3-GP"
			(at 0.064008 -3.993896 180)
			(unlocked yes)
			(layer "F.Fab")
			(hide yes)
			(effects
				(font
					(size 1.016 1.016)
					(thickness 0.1524)
				)
			)
		)
		(property "Device Type" "R402H16"
			(at 0.064008 -5.517896 180)
			(unlocked yes)
			(layer "F.Fab")
			(hide yes)
			(effects
				(font
					(size 1.016 1.016)
					(thickness 0.1524)
				)
			)
		)
		(duplicate_pad_numbers_are_jumpers no)
		(fp_line
			(start 0.508 -0.9398)
			(end -0.508 -0.9398)
			(stroke
				(width 0.1524)
				(type default)
			)
			(layer "F.SilkS")
		)
		(fp_line
			(start -0.508 -0.9398)
			(end -0.508 0.9398)
			(stroke
				(width 0.1524)
				(type default)
			)
			(layer "F.SilkS")
		)
		(fp_rect
			(start -0.508 0.9398)
			(end 0.508 -0.9398)
			(stroke
				(width 0)
				(type default)
			)
			(fill no)
			(layer "F.CrtYd")
		)
		(fp_rect
			(start -0.508 0.9398)
			(end 0.508 -0.9398)
			(stroke
				(width 0)
				(type default)
			)
			(fill no)
			(layer "F.Fab")
		)
		(pad "1" smd custom
			(at 0 -0.4445 180)
			(size 0.1397 0.1397)
			(layers "F.Cu" "F.Mask" "F.Paste")
			(net "P3V3")
			(options
				(clearance outline)
				(anchor circle)
			)
			(primitives
				(gr_poly
					(pts
						(arc
							(start -0.1778 -0.2794)
							(mid -0.249642 -0.249642)
							(end -0.2794 -0.1778)
						)
						(arc
							(start -0.2794 0.1778)
							(mid -0.249642 0.249642)
							(end -0.1778 0.2794)
						)
						(arc
							(start 0.1778 0.2794)
							(mid 0.249642 0.249642)
							(end 0.2794 0.1778)
						)
						(arc
							(start 0.2794 -0.1778)
							(mid 0.249642 -0.249642)
							(end 0.1778 -0.2794)
						)
					)
					(width 0)
					(fill yes)
				)
			)
		)
		(pad "2" smd custom
			(at 0 0.4445 180)
			(size 0.1397 0.1397)
			(layers "F.Cu" "F.Mask" "F.Paste")
			(net "SW_PWR_HDD12")
			(options
				(clearance outline)
				(anchor circle)
			)
			(primitives
				(gr_poly
					(pts
						(arc
							(start -0.1778 -0.2794)
							(mid -0.249642 -0.249642)
							(end -0.2794 -0.1778)
						)
						(arc
							(start -0.2794 0.1778)
							(mid -0.249642 0.249642)
							(end -0.1778 0.2794)
						)
						(arc
							(start 0.1778 0.2794)
							(mid 0.249642 0.249642)
							(end 0.2794 0.1778)
						)
						(arc
							(start 0.2794 -0.1778)
							(mid 0.249642 -0.249642)
							(end 0.1778 -0.2794)
						)
					)
					(width 0)
					(fill yes)
				)
			)
		)
	)
	(footprint ""
		(layer "F.Cu")
		(at 27.406346 -405.6761 90)
		(property "Reference" "C350"
			(at 0 0 90)
			(layer "F.SilkS")
			(hide yes)
			(effects
				(font
					(size 1.27 1.27)
				)
			)
		)
		(property "Value" "SC10U25V5KX-GP"
			(at -0.0762 -6.1214 90)
			(unlocked yes)
			(layer "F.Fab")
			(hide yes)
			(effects
				(font
					(size 1.016 1.016)
					(thickness 0.1524)
				)
			)
		)
		(property "Device Type" "C805H56"
			(at -0.0762 -8.1534 90)
			(unlocked yes)
			(layer "F.Fab")
			(hide yes)
			(effects
				(font
					(size 1.016 1.016)
					(thickness 0.1524)
				)
			)
		)
		(duplicate_pad_numbers_are_jumpers no)
		(fp_line
			(start 0.635 0)
			(end -0.635 0)
			(stroke
				(width 0.508)
				(type default)
			)
			(layer "F.SilkS")
		)
		(fp_rect
			(start -0.9652 1.778)
			(end 0.9652 -1.778)
			(stroke
				(width 0)
				(type default)
			)
			(fill no)
			(layer "F.CrtYd")
		)
		(fp_poly
			(pts
				(xy -0.9652 -1.778) (xy 0.9652 -1.778) (xy 0.9652 1.778) (xy -0.9652 1.778)
			)
			(stroke
				(width 0)
				(type default)
			)
			(fill no)
			(layer "F.Fab")
		)
		(pad "1" smd rect
			(at 0 -0.9652 90)
			(size 1.397 1.143)
			(layers "F.Cu" "F.Mask" "F.Paste")
			(net "P12V")
		)
		(pad "2" smd rect
			(at 0 0.9652 90)
			(size 1.397 1.143)
			(layers "F.Cu" "F.Mask" "F.Paste")
			(net "GND")
		)
	)
	(footprint ""
		(layer "F.Cu")
		(at 37.083746 -437.5277 90)
		(property "Reference" "R247"
			(at 0 0 90)
			(layer "F.SilkS")
			(hide yes)
			(effects
				(font
					(size 1.27 1.27)
				)
			)
		)
		(property "Value" "1KR2F-3-GP"
			(at 0.064008 -3.993896 90)
			(unlocked yes)
			(layer "F.Fab")
			(hide yes)
			(effects
				(font
					(size 1.016 1.016)
					(thickness 0.1524)
				)
			)
		)
		(property "Device Type" "R402H16"
			(at 0.064008 -5.517896 90)
			(unlocked yes)
			(layer "F.Fab")
			(hide yes)
			(effects
				(font
					(size 1.016 1.016)
					(thickness 0.1524)
				)
			)
		)
		(duplicate_pad_numbers_are_jumpers no)
		(fp_line
			(start 0.508 -0.9398)
			(end -0.508 -0.9398)
			(stroke
				(width 0.1524)
				(type default)
			)
			(layer "F.SilkS")
		)
		(fp_line
			(start -0.508 -0.9398)
			(end -0.508 0.9398)
			(stroke
				(width 0.1524)
				(type default)
			)
			(layer "F.SilkS")
		)
		(fp_rect
			(start -0.508 0.9398)
			(end 0.508 -0.9398)
			(stroke
				(width 0)
				(type default)
			)
			(fill no)
			(layer "F.CrtYd")
		)
		(fp_rect
			(start -0.508 0.9398)
			(end 0.508 -0.9398)
			(stroke
				(width 0)
				(type default)
			)
			(fill no)
			(layer "F.Fab")
		)
		(pad "1" smd custom
			(at 0 -0.4445 90)
			(size 0.1397 0.1397)
			(layers "F.Cu" "F.Mask" "F.Paste")
			(net "P3V3")
			(options
				(clearance outline)
				(anchor circle)
			)
			(primitives
				(gr_poly
					(pts
						(arc
							(start -0.1778 -0.2794)
							(mid -0.249642 -0.249642)
							(end -0.2794 -0.1778)
						)
						(arc
							(start -0.2794 0.1778)
							(mid -0.249642 0.249642)
							(end -0.1778 0.2794)
						)
						(arc
							(start 0.1778 0.2794)
							(mid 0.249642 0.249642)
							(end 0.2794 0.1778)
						)
						(arc
							(start 0.2794 -0.1778)
							(mid 0.249642 -0.249642)
							(end 0.1778 -0.2794)
						)
					)
					(width 0)
					(fill yes)
				)
			)
		)
		(pad "2" smd custom
			(at 0 0.4445 90)
			(size 0.1397 0.1397)
			(layers "F.Cu" "F.Mask" "F.Paste")
			(net "SW_PWR_HDD10")
			(options
				(clearance outline)
				(anchor circle)
			)
			(primitives
				(gr_poly
					(pts
						(arc
							(start -0.1778 -0.2794)
							(mid -0.249642 -0.249642)
							(end -0.2794 -0.1778)
						)
						(arc
							(start -0.2794 0.1778)
							(mid -0.249642 0.249642)
							(end -0.1778 0.2794)
						)
						(arc
							(start 0.1778 0.2794)
							(mid 0.249642 0.249642)
							(end 0.2794 0.1778)
						)
						(arc
							(start 0.2794 -0.1778)
							(mid 0.249642 -0.249642)
							(end 0.1778 -0.2794)
						)
					)
					(width 0)
					(fill yes)
				)
			)
		)
	)
	(footprint ""
		(layer "F.Cu")
		(at 192.151 -190.754 90)
		(property "Reference" "R148"
			(at 0 0 90)
			(layer "F.SilkS")
			(hide yes)
			(effects
				(font
					(size 1.27 1.27)
				)
			)
		)
		(property "Value" "4K7R2J-2-GP"
			(at 0.064008 -3.993896 90)
			(unlocked yes)
			(layer "F.Fab")
			(hide yes)
			(effects
				(font
					(size 1.016 1.016)
					(thickness 0.1524)
				)
			)
		)
		(property "Device Type" "R402H16"
			(at 0.064008 -5.517896 90)
			(unlocked yes)
			(layer "F.Fab")
			(hide yes)
			(effects
				(font
					(size 1.016 1.016)
					(thickness 0.1524)
				)
			)
		)
		(duplicate_pad_numbers_are_jumpers no)
		(fp_line
			(start 0.508 -0.9398)
			(end -0.508 -0.9398)
			(stroke
				(width 0.1524)
				(type default)
			)
			(layer "F.SilkS")
		)
		(fp_line
			(start -0.508 -0.9398)
			(end -0.508 0.9398)
			(stroke
				(width 0.1524)
				(type default)
			)
			(layer "F.SilkS")
		)
		(fp_rect
			(start -0.508 0.9398)
			(end 0.508 -0.9398)
			(stroke
				(width 0)
				(type default)
			)
			(fill no)
			(layer "F.CrtYd")
		)
		(fp_rect
			(start -0.508 0.9398)
			(end 0.508 -0.9398)
			(stroke
				(width 0)
				(type default)
			)
			(fill no)
			(layer "F.Fab")
		)
		(pad "1" smd custom
			(at 0 -0.4445 90)
			(size 0.1397 0.1397)
			(layers "F.Cu" "F.Mask" "F.Paste")
			(net "P12V")
			(options
				(clearance outline)
				(anchor circle)
			)
			(primitives
				(gr_poly
					(pts
						(arc
							(start -0.1778 -0.2794)
							(mid -0.249642 -0.249642)
							(end -0.2794 -0.1778)
						)
						(arc
							(start -0.2794 0.1778)
							(mid -0.249642 0.249642)
							(end -0.1778 0.2794)
						)
						(arc
							(start 0.1778 0.2794)
							(mid 0.249642 0.249642)
							(end 0.2794 0.1778)
						)
						(arc
							(start 0.2794 -0.1778)
							(mid 0.249642 -0.249642)
							(end 0.1778 -0.2794)
						)
					)
					(width 0)
					(fill yes)
				)
			)
		)
		(pad "2" smd custom
			(at 0 0.4445 90)
			(size 0.1397 0.1397)
			(layers "F.Cu" "F.Mask" "F.Paste")
			(net "SW_HDD3_R")
			(options
				(clearance outline)
				(anchor circle)
			)
			(primitives
				(gr_poly
					(pts
						(arc
							(start -0.1778 -0.2794)
							(mid -0.249642 -0.249642)
							(end -0.2794 -0.1778)
						)
						(arc
							(start -0.2794 0.1778)
							(mid -0.249642 0.249642)
							(end -0.1778 0.2794)
						)
						(arc
							(start 0.1778 0.2794)
							(mid 0.249642 0.249642)
							(end 0.2794 0.1778)
						)
						(arc
							(start 0.2794 -0.1778)
							(mid 0.249642 -0.249642)
							(end 0.1778 -0.2794)
						)
					)
					(width 0)
					(fill yes)
				)
			)
		)
	)
	(footprint ""
		(layer "F.Cu")
		(at 39.743634 -453.874886 90)
		(property "Reference" "R171"
			(at 0 0 90)
			(layer "F.SilkS")
			(hide yes)
			(effects
				(font
					(size 1.27 1.27)
				)
			)
		)
		(property "Value" "402R2F-GP"
			(at 0.064008 -3.993896 90)
			(unlocked yes)
			(layer "F.Fab")
			(hide yes)
			(effects
				(font
					(size 1.016 1.016)
					(thickness 0.1524)
				)
			)
		)
		(property "Device Type" "R402H16"
			(at 0.064008 -5.517896 90)
			(unlocked yes)
			(layer "F.Fab")
			(hide yes)
			(effects
				(font
					(size 1.016 1.016)
					(thickness 0.1524)
				)
			)
		)
		(duplicate_pad_numbers_are_jumpers no)
		(fp_line
			(start 0.508 -0.9398)
			(end -0.508 -0.9398)
			(stroke
				(width 0.1524)
				(type default)
			)
			(layer "F.SilkS")
		)
		(fp_line
			(start -0.508 -0.9398)
			(end -0.508 0.9398)
			(stroke
				(width 0.1524)
				(type default)
			)
			(layer "F.SilkS")
		)
		(fp_rect
			(start -0.508 0.9398)
			(end 0.508 -0.9398)
			(stroke
				(width 0)
				(type default)
			)
			(fill no)
			(layer "F.CrtYd")
		)
		(fp_rect
			(start -0.508 0.9398)
			(end 0.508 -0.9398)
			(stroke
				(width 0)
				(type default)
			)
			(fill no)
			(layer "F.Fab")
		)
		(pad "1" smd custom
			(at 0 -0.4445 90)
			(size 0.1397 0.1397)
			(layers "F.Cu" "F.Mask" "F.Paste")
			(net "P5VB_HDD5_LED")
			(options
				(clearance outline)
				(anchor circle)
			)
			(primitives
				(gr_poly
					(pts
						(arc
							(start -0.1778 -0.2794)
							(mid -0.249642 -0.249642)
							(end -0.2794 -0.1778)
						)
						(arc
							(start -0.2794 0.1778)
							(mid -0.249642 0.249642)
							(end -0.1778 0.2794)
						)
						(arc
							(start 0.1778 0.2794)
							(mid 0.249642 0.249642)
							(end 0.2794 0.1778)
						)
						(arc
							(start 0.2794 -0.1778)
							(mid 0.249642 -0.249642)
							(end 0.1778 -0.2794)
						)
					)
					(width 0)
					(fill yes)
				)
			)
		)
		(pad "2" smd custom
			(at 0 0.4445 90)
			(size 0.1397 0.1397)
			(layers "F.Cu" "F.Mask" "F.Paste")
			(net "DRV_ACT_5")
			(options
				(clearance outline)
				(anchor circle)
			)
			(primitives
				(gr_poly
					(pts
						(arc
							(start -0.1778 -0.2794)
							(mid -0.249642 -0.249642)
							(end -0.2794 -0.1778)
						)
						(arc
							(start -0.2794 0.1778)
							(mid -0.249642 0.249642)
							(end -0.1778 0.2794)
						)
						(arc
							(start 0.1778 0.2794)
							(mid 0.249642 0.249642)
							(end 0.2794 0.1778)
						)
						(arc
							(start 0.2794 -0.1778)
							(mid 0.249642 -0.249642)
							(end 0.1778 -0.2794)
						)
					)
					(width 0)
					(fill yes)
				)
			)
		)
	)
	(footprint ""
		(layer "F.Cu")
		(at 33.2613 -274.5994 90)
		(property "Reference" "C37"
			(at 0 0 90)
			(layer "F.SilkS")
			(hide yes)
			(effects
				(font
					(size 1.27 1.27)
				)
			)
		)
		(property "Value" "SCD01U50V2KX-1GP"
			(at 1.1811 -2.7051 90)
			(unlocked yes)
			(layer "F.Fab")
			(hide yes)
			(effects
				(font
					(size 1.016 1.016)
					(thickness 0.1524)
				)
			)
		)
		(property "Device Type" "C402H22"
			(at 1.1811 -4.2291 90)
			(unlocked yes)
			(layer "F.Fab")
			(hide yes)
			(effects
				(font
					(size 1.016 1.016)
					(thickness 0.1524)
				)
			)
		)
		(duplicate_pad_numbers_are_jumpers no)
		(fp_rect
			(start -0.4318 0.9525)
			(end 0.4318 -0.9525)
			(stroke
				(width 0)
				(type default)
			)
			(fill no)
			(layer "F.CrtYd")
		)
		(fp_rect
			(start -0.4318 0.9525)
			(end 0.4318 -0.9525)
			(stroke
				(width 0)
				(type default)
			)
			(fill no)
			(layer "F.Fab")
		)
		(pad "1" smd custom
			(at 0 -0.4445 90)
			(size 0.1524 0.1524)
			(layers "F.Cu" "F.Mask" "F.Paste")
			(net "SEB_BA_TX-")
			(options
				(clearance outline)
				(anchor circle)
			)
			(primitives
				(gr_poly
					(pts
						(arc
							(start 0.3048 -0.2032)
							(mid 0.275042 -0.275042)
							(end 0.2032 -0.3048)
						)
						(arc
							(start -0.2032 -0.3048)
							(mid -0.275042 -0.275042)
							(end -0.3048 -0.2032)
						)
						(arc
							(start -0.3048 0.2032)
							(mid -0.275042 0.275042)
							(end -0.2032 0.3048)
						)
						(arc
							(start 0.2032 0.3048)
							(mid 0.275042 0.275042)
							(end 0.3048 0.2032)
						)
					)
					(width 0)
					(fill yes)
				)
			)
		)
		(pad "2" smd custom
			(at 0 0.4445 90)
			(size 0.1524 0.1524)
			(layers "F.Cu" "F.Mask" "F.Paste")
			(net "SEB_BA_RX-")
			(options
				(clearance outline)
				(anchor circle)
			)
			(primitives
				(gr_poly
					(pts
						(arc
							(start 0.3048 -0.2032)
							(mid 0.275042 -0.275042)
							(end 0.2032 -0.3048)
						)
						(arc
							(start -0.2032 -0.3048)
							(mid -0.275042 -0.275042)
							(end -0.3048 -0.2032)
						)
						(arc
							(start -0.3048 0.2032)
							(mid -0.275042 0.275042)
							(end -0.2032 0.3048)
						)
						(arc
							(start 0.2032 0.3048)
							(mid 0.275042 0.275042)
							(end 0.3048 0.2032)
						)
					)
					(width 0)
					(fill yes)
				)
			)
		)
	)
	(footprint ""
		(layer "F.Cu")
		(at 202.864974 -493.875822 -90)
		(property "Reference" "R422"
			(at 0 0 270)
			(layer "F.SilkS")
			(hide yes)
			(effects
				(font
					(size 1.27 1.27)
				)
			)
		)
		(property "Value" "4K7R2J-2-GP"
			(at 0.064008 -3.993896 270)
			(unlocked yes)
			(layer "F.Fab")
			(hide yes)
			(effects
				(font
					(size 1.016 1.016)
					(thickness 0.1524)
				)
			)
		)
		(property "Device Type" "R402H16"
			(at 0.064008 -5.517896 270)
			(unlocked yes)
			(layer "F.Fab")
			(hide yes)
			(effects
				(font
					(size 1.016 1.016)
					(thickness 0.1524)
				)
			)
		)
		(duplicate_pad_numbers_are_jumpers no)
		(fp_line
			(start -0.508 -0.9398)
			(end -0.508 0.9398)
			(stroke
				(width 0.1524)
				(type default)
			)
			(layer "F.SilkS")
		)
		(fp_line
			(start 0.508 -0.9398)
			(end -0.508 -0.9398)
			(stroke
				(width 0.1524)
				(type default)
			)
			(layer "F.SilkS")
		)
		(fp_rect
			(start -0.508 0.9398)
			(end 0.508 -0.9398)
			(stroke
				(width 0)
				(type default)
			)
			(fill no)
			(layer "F.CrtYd")
		)
		(fp_rect
			(start -0.508 0.9398)
			(end 0.508 -0.9398)
			(stroke
				(width 0)
				(type default)
			)
			(fill no)
			(layer "F.Fab")
		)
		(pad "1" smd custom
			(at 0 -0.4445 270)
			(size 0.1397 0.1397)
			(layers "F.Cu" "F.Mask" "F.Paste")
			(net "P3V3")
			(options
				(clearance outline)
				(anchor circle)
			)
			(primitives
				(gr_poly
					(pts
						(arc
							(start -0.1778 -0.2794)
							(mid -0.249642 -0.249642)
							(end -0.2794 -0.1778)
						)
						(arc
							(start -0.2794 0.1778)
							(mid -0.249642 0.249642)
							(end -0.1778 0.2794)
						)
						(arc
							(start 0.1778 0.2794)
							(mid 0.249642 0.249642)
							(end 0.2794 0.1778)
						)
						(arc
							(start 0.2794 -0.1778)
							(mid 0.249642 -0.249642)
							(end 0.1778 -0.2794)
						)
					)
					(width 0)
					(fill yes)
				)
			)
		)
		(pad "2" smd custom
			(at 0 0.4445 270)
			(size 0.1397 0.1397)
			(layers "F.Cu" "F.Mask" "F.Paste")
			(net "SAS2X28_B_HDD0_FLT")
			(options
				(clearance outline)
				(anchor circle)
			)
			(primitives
				(gr_poly
					(pts
						(arc
							(start -0.1778 -0.2794)
							(mid -0.249642 -0.249642)
							(end -0.2794 -0.1778)
						)
						(arc
							(start -0.2794 0.1778)
							(mid -0.249642 0.249642)
							(end -0.1778 0.2794)
						)
						(arc
							(start 0.1778 0.2794)
							(mid 0.249642 0.249642)
							(end 0.2794 0.1778)
						)
						(arc
							(start 0.2794 -0.1778)
							(mid 0.249642 -0.249642)
							(end 0.1778 -0.2794)
						)
					)
					(width 0)
					(fill yes)
				)
			)
		)
	)
	(footprint ""
		(layer "F.Cu")
		(at 224.789746 -144.9197 90)
		(property "Reference" "R143"
			(at 0 0 90)
			(layer "F.SilkS")
			(hide yes)
			(effects
				(font
					(size 1.27 1.27)
				)
			)
		)
		(property "Value" "402R2F-GP"
			(at 0.064008 -3.993896 90)
			(unlocked yes)
			(layer "F.Fab")
			(hide yes)
			(effects
				(font
					(size 1.016 1.016)
					(thickness 0.1524)
				)
			)
		)
		(property "Device Type" "R402H16"
			(at 0.064008 -5.517896 90)
			(unlocked yes)
			(layer "F.Fab")
			(hide yes)
			(effects
				(font
					(size 1.016 1.016)
					(thickness 0.1524)
				)
			)
		)
		(duplicate_pad_numbers_are_jumpers no)
		(fp_line
			(start 0.508 -0.9398)
			(end -0.508 -0.9398)
			(stroke
				(width 0.1524)
				(type default)
			)
			(layer "F.SilkS")
		)
		(fp_line
			(start -0.508 -0.9398)
			(end -0.508 0.9398)
			(stroke
				(width 0.1524)
				(type default)
			)
			(layer "F.SilkS")
		)
		(fp_rect
			(start -0.508 0.9398)
			(end 0.508 -0.9398)
			(stroke
				(width 0)
				(type default)
			)
			(fill no)
			(layer "F.CrtYd")
		)
		(fp_rect
			(start -0.508 0.9398)
			(end 0.508 -0.9398)
			(stroke
				(width 0)
				(type default)
			)
			(fill no)
			(layer "F.Fab")
		)
		(pad "1" smd custom
			(at 0 -0.4445 90)
			(size 0.1397 0.1397)
			(layers "F.Cu" "F.Mask" "F.Paste")
			(net "P5VA_HDD3_LED")
			(options
				(clearance outline)
				(anchor circle)
			)
			(primitives
				(gr_poly
					(pts
						(arc
							(start -0.1778 -0.2794)
							(mid -0.249642 -0.249642)
							(end -0.2794 -0.1778)
						)
						(arc
							(start -0.2794 0.1778)
							(mid -0.249642 0.249642)
							(end -0.1778 0.2794)
						)
						(arc
							(start 0.1778 0.2794)
							(mid 0.249642 0.249642)
							(end 0.2794 0.1778)
						)
						(arc
							(start 0.2794 -0.1778)
							(mid 0.249642 -0.249642)
							(end 0.1778 -0.2794)
						)
					)
					(width 0)
					(fill yes)
				)
			)
		)
		(pad "2" smd custom
			(at 0 0.4445 90)
			(size 0.1397 0.1397)
			(layers "F.Cu" "F.Mask" "F.Paste")
			(net "DRV_ACT_3")
			(options
				(clearance outline)
				(anchor circle)
			)
			(primitives
				(gr_poly
					(pts
						(arc
							(start -0.1778 -0.2794)
							(mid -0.249642 -0.249642)
							(end -0.2794 -0.1778)
						)
						(arc
							(start -0.2794 0.1778)
							(mid -0.249642 0.249642)
							(end -0.1778 0.2794)
						)
						(arc
							(start 0.1778 0.2794)
							(mid 0.249642 0.249642)
							(end 0.2794 0.1778)
						)
						(arc
							(start 0.2794 -0.1778)
							(mid 0.249642 -0.249642)
							(end 0.1778 -0.2794)
						)
					)
					(width 0)
					(fill yes)
				)
			)
		)
	)
)
